# BASEBOARD_FAB2 (Tioga Pass) — schematic netlist excerpt (pin names and nets, part order shuffled) for the footprints in the layout excerpt that follows; sources: Cadence DE-HDL packaged netlist, KiCad conversion of Wiwynn_Tioga_Pass_MB.brd

C5P7  CAP  22UF 4V 20% X6S  pkg 0805LF  page 42 : A = PVSA_CPU0 ; B = GND
R2L18  RES  1.00K 1% CHIP  pkg 0402  page 173 : A = PD_SATA0_CONTROLLER_TYPE_R ; B = GND
C5P37  CAP  47UF 4V 20% X6S  pkg 0805  page 42 : A = PVCCIN_CPU0 ; B = GND

(kicad_pcb
	(version 20260206)
	(generator "pcbnew")
	(generator_version "10.0")
	(general
		(thickness 1.6)
		(legacy_teardrops no)
	)
	(paper "A4")
	(title_block
		(title "Wiwynn_Tioga_Pass_MB.brd")
		(comment 1 "Tioga Pass / footprints 4388-4390 of 4770")
	)
	(layers
		(0 "F.Cu" signal "TOP")
		(4 "In1.Cu" signal "L2GND")
		(6 "In2.Cu" signal "L3")
		(8 "In3.Cu" signal "L4GND")
		(10 "In4.Cu" signal "L5")
		(12 "In5.Cu" signal "L6GND")
		(14 "In6.Cu" signal "L7VCC")
		(16 "In7.Cu" signal "L8VCC")
		(18 "In8.Cu" signal "L9GND")
		(20 "In9.Cu" signal "L10")
		(22 "In10.Cu" signal "L11GND")
		(24 "In11.Cu" signal "L12")
		(26 "In12.Cu" signal "L13GND")
		(2 "B.Cu" signal "BOTTOM")
		(9 "F.Adhes" user "F.Adhesive")
		(11 "B.Adhes" user "B.Adhesive")
		(13 "F.Paste" user "Package Geometry/Pastemask Top")
		(15 "B.Paste" user "Package Geometry/Pastemask Bottom")
		(5 "F.SilkS" user "Ref Des/Silkscreen Top")
		(7 "B.SilkS" user "Ref Des/Silkscreen Bottom")
		(1 "F.Mask" user "Board Geometry/Soldermask Top")
		(3 "B.Mask" user "Board Geometry/Soldermask Bottom")
		(17 "Dwgs.User" user "User.Drawings")
		(19 "Cmts.User" user "User.Comments")
		(21 "Eco1.User" user "User.Eco1")
		(23 "Eco2.User" user "User.Eco2")
		(25 "Edge.Cuts" user "Board Geometry/Outline")
		(27 "Margin" user)
		(31 "F.CrtYd" user "Package Geometry/Place Bound Top")
		(29 "B.CrtYd" user "Package Geometry/Place Bound Bottom")
		(35 "F.Fab" user "Ref Des/Assembly Top")
		(33 "B.Fab" user "Ref Des/Assembly Bottom")
	)
	(footprint ""
		(layer "B.Cu")
		(at 262.271256 -83.74634 90)
		(property "Reference" "C5P7"
			(at 0 0 90)
			(layer "B.SilkS")
			(hide yes)
			(effects
				(font
					(size 1.27 1.27)
				)
				(justify mirror)
			)
		)
		(property "Value" ""
			(at 0 0 90)
			(layer "B.Fab")
			(effects
				(font
					(size 1.27 1.27)
				)
				(justify mirror)
			)
		)
		(duplicate_pad_numbers_are_jumpers no)
		(fp_poly
			(pts
				(xy 0.7239 -0.2159) (xy -0.7239 -0.2159) (xy -0.7239 1.9939) (xy 0.7239 1.9939)
			)
			(stroke
				(width 0)
				(type default)
			)
			(fill no)
			(layer "B.CrtYd")
		)
		(fp_line
			(start 0.7239 -0.2159)
			(end 0.7239 1.9939)
			(stroke
				(width 0.1)
				(type default)
			)
			(layer "B.Fab")
		)
		(fp_line
			(start -0.7239 -0.2159)
			(end 0.7239 -0.2159)
			(stroke
				(width 0.1)
				(type default)
			)
			(layer "B.Fab")
		)
		(fp_line
			(start 0.7239 1.9939)
			(end -0.7239 1.9939)
			(stroke
				(width 0.1)
				(type default)
			)
			(layer "B.Fab")
		)
		(fp_line
			(start -0.7239 1.9939)
			(end -0.7239 -0.2159)
			(stroke
				(width 0.1)
				(type default)
			)
			(layer "B.Fab")
		)
		(pad "1" smd rect
			(at 0 0 270)
			(size 1.27 1.016)
			(layers "B.Cu" "B.Mask" "B.Paste")
			(net "PVSA_CPU0")
		)
		(pad "2" smd rect
			(at 0 1.778 270)
			(size 1.27 1.016)
			(layers "B.Cu" "B.Mask" "B.Paste")
			(net "GND")
		)
		(zone
			(layer "B.Cu")
			(hatch none 0.5)
			(connect_pads
				(clearance 0)
			)
			(min_thickness 0.25)
			(keepout
				(tracks not_allowed)
				(vias allowed)
				(pads allowed)
				(copperpour not_allowed)
				(footprints allowed)
			)
			(placement
				(enabled no)
				(sheetname "")
			)
			(fill
				(thermal_gap 0.5)
				(thermal_bridge_width 0.5)
				(island_removal_mode 0)
			)
			(polygon
				(pts
					(xy 262.779256 -84.38134) (xy 262.779256 -83.11134) (xy 263.541256 -83.11134) (xy 263.541256 -84.38134)
				)
			)
		)
	)
	(footprint ""
		(layer "B.Cu")
		(at 433.243482 -148.520658 90)
		(property "Reference" "R2L18"
			(at 0 0 90)
			(layer "B.SilkS")
			(hide yes)
			(effects
				(font
					(size 1.27 1.27)
				)
				(justify mirror)
			)
		)
		(property "Value" ""
			(at 0 0 90)
			(layer "B.Fab")
			(effects
				(font
					(size 1.27 1.27)
				)
				(justify mirror)
			)
		)
		(duplicate_pad_numbers_are_jumpers no)
		(fp_poly
			(pts
				(xy 0.2794 -0.1016) (xy -0.2794 -0.1016) (xy -0.2794 0.9906) (xy 0.2794 0.9906)
			)
			(stroke
				(width 0)
				(type default)
			)
			(fill no)
			(layer "B.CrtYd")
		)
		(fp_line
			(start 0.2794 -0.1016)
			(end 0.2794 0.9906)
			(stroke
				(width 0.1)
				(type default)
			)
			(layer "B.Fab")
		)
		(fp_line
			(start -0.2794 -0.1016)
			(end 0.2794 -0.1016)
			(stroke
				(width 0.1)
				(type default)
			)
			(layer "B.Fab")
		)
		(fp_line
			(start 0.2794 0.9906)
			(end -0.2794 0.9906)
			(stroke
				(width 0.1)
				(type default)
			)
			(layer "B.Fab")
		)
		(fp_line
			(start -0.2794 0.9906)
			(end -0.2794 -0.1016)
			(stroke
				(width 0.1)
				(type default)
			)
			(layer "B.Fab")
		)
		(pad "1" smd rect
			(at 0 0 270)
			(size 0.508 0.508)
			(layers "B.Cu" "B.Mask" "B.Paste")
			(net "PD_SATA0_CONTROLLER_TYPE_R")
		)
		(pad "2" smd rect
			(at 0 0.889 270)
			(size 0.508 0.508)
			(layers "B.Cu" "B.Mask" "B.Paste")
			(net "GND")
		)
		(zone
			(layer "B.Cu")
			(hatch none 0.5)
			(connect_pads
				(clearance 0)
			)
			(min_thickness 0.25)
			(keepout
				(tracks allowed)
				(vias not_allowed)
				(pads allowed)
				(copperpour not_allowed)
				(footprints allowed)
			)
			(placement
				(enabled no)
				(sheetname "")
			)
			(fill
				(thermal_gap 0.5)
				(thermal_bridge_width 0.5)
				(island_removal_mode 0)
			)
			(polygon
				(pts
					(xy 433.497482 -148.774658) (xy 433.497482 -148.266658) (xy 433.878482 -148.266658) (xy 433.878482 -148.774658)
				)
			)
		)
		(zone
			(layer "B.Cu")
			(hatch none 0.5)
			(connect_pads
				(clearance 0)
			)
			(min_thickness 0.25)
			(keepout
				(tracks not_allowed)
				(vias allowed)
				(pads allowed)
				(copperpour not_allowed)
				(footprints allowed)
			)
			(placement
				(enabled no)
				(sheetname "")
			)
			(fill
				(thermal_gap 0.5)
				(thermal_bridge_width 0.5)
				(island_removal_mode 0)
			)
			(polygon
				(pts
					(xy 433.878482 -148.774658) (xy 433.878482 -148.266658) (xy 433.497482 -148.266658) (xy 433.497482 -148.774658)
				)
			)
		)
	)
	(footprint ""
		(layer "B.Cu")
		(at 258.548886 -73.51014)
		(property "Reference" "C5P37"
			(at 0 0 0)
			(layer "B.SilkS")
			(hide yes)
			(effects
				(font
					(size 1.27 1.27)
				)
				(justify mirror)
			)
		)
		(property "Value" ""
			(at 0 0 0)
			(layer "B.Fab")
			(effects
				(font
					(size 1.27 1.27)
				)
				(justify mirror)
			)
		)
		(duplicate_pad_numbers_are_jumpers no)
		(fp_poly
			(pts
				(xy 0.7239 -0.2159) (xy -0.7239 -0.2159) (xy -0.7239 1.9939) (xy 0.7239 1.9939)
			)
			(stroke
				(width 0)
				(type default)
			)
			(fill no)
			(layer "B.CrtYd")
		)
		(fp_line
			(start -0.7239 -0.2159)
			(end 0.7239 -0.2159)
			(stroke
				(width 0.1)
				(type default)
			)
			(layer "B.Fab")
		)
		(fp_line
			(start -0.7239 1.9939)
			(end -0.7239 -0.2159)
			(stroke
				(width 0.1)
				(type default)
			)
			(layer "B.Fab")
		)
		(fp_line
			(start 0.7239 -0.2159)
			(end 0.7239 1.9939)
			(stroke
				(width 0.1)
				(type default)
			)
			(layer "B.Fab")
		)
		(fp_line
			(start 0.7239 1.9939)
			(end -0.7239 1.9939)
			(stroke
				(width 0.1)
				(type default)
			)
			(layer "B.Fab")
		)
		(pad "1" smd rect
			(at 0 0 180)
			(size 1.27 1.016)
			(layers "B.Cu" "B.Mask" "B.Paste")
			(net "PVCCIN_CPU0")
		)
		(pad "2" smd rect
			(at 0 1.778 180)
			(size 1.27 1.016)
			(layers "B.Cu" "B.Mask" "B.Paste")
			(net "GND")
		)
		(zone
			(layer "B.Cu")
			(hatch none 0.5)
			(connect_pads
				(clearance 0)
			)
			(min_thickness 0.25)
			(keepout
				(tracks not_allowed)
				(vias allowed)
				(pads allowed)
				(copperpour not_allowed)
				(footprints allowed)
			)
			(placement
				(enabled no)
				(sheetname "")
			)
			(fill
				(thermal_gap 0.5)
				(thermal_bridge_width 0.5)
				(island_removal_mode 0)
			)
			(polygon
				(pts
					(xy 259.183886 -73.00214) (xy 257.913886 -73.00214) (xy 257.913886 -72.24014) (xy 259.183886 -72.24014)
				)
			)
		)
	)
)
